(kicad_pcb
	(version 20260206)
	(generator "pcbnew")
	(generator_version "10.0")
	(general
		(thickness 1.6)
		(legacy_teardrops no)
	)
	(paper "A4")
	(title_block
		(title "Bryce Canyon_F.DPB_16315-1-OCP.brd")
		(comment 1 "Bryce Canyon / footprints 1654-1661 of 2223")
	)
	(layers
		(0 "F.Cu" signal "TOP")
		(4 "In1.Cu" signal "L2GND")
		(6 "In2.Cu" signal "L3")
		(8 "In3.Cu" signal "L4GND")
		(10 "In4.Cu" signal "L5")
		(12 "In5.Cu" signal "L6VCC")
		(14 "In6.Cu" signal "L7VCC")
		(16 "In7.Cu" signal "L8")
		(18 "In8.Cu" signal "L9GND")
		(20 "In9.Cu" signal "L10")
		(22 "In10.Cu" signal "L11GND")
		(2 "B.Cu" signal "BOTTOM")
		(9 "F.Adhes" user "F.Adhesive")
		(11 "B.Adhes" user "B.Adhesive")
		(13 "F.Paste" user "Package Geometry/Pastemask Top")
		(15 "B.Paste" user "Package Geometry/Pastemask Bottom")
		(5 "F.SilkS" user "Ref Des/Silkscreen Top")
		(7 "B.SilkS" user "Ref Des/Silkscreen Bottom")
		(1 "F.Mask" user "Board Geometry/Soldermask Top")
		(3 "B.Mask" user "Board Geometry/Soldermask Bottom")
		(17 "Dwgs.User" user "User.Drawings")
		(19 "Cmts.User" user "User.Comments")
		(21 "Eco1.User" user "User.Eco1")
		(23 "Eco2.User" user "User.Eco2")
		(25 "Edge.Cuts" user "Board Geometry/Outline")
		(27 "Margin" user)
		(31 "F.CrtYd" user "Package Geometry/Place Bound Top")
		(29 "B.CrtYd" user "Package Geometry/Place Bound Bottom")
		(35 "F.Fab" user "Ref Des/Assembly Top")
		(33 "B.Fab" user "Ref Des/Assembly Bottom")
	)
	(footprint ""
		(layer "F.Cu")
		(at 221.3864 -376.62104 -90)
		(property "Reference" "C535"
			(at 0 0 270)
			(layer "F.SilkS")
			(hide yes)
			(effects
				(font
					(size 1.27 1.27)
				)
			)
		)
		(property "Value" "SC1U16V3KX-5GP"
			(at 0 -2.8194 270)
			(unlocked yes)
			(layer "F.Fab")
			(hide yes)
			(effects
				(font
					(size 1.016 1.016)
					(thickness 0.1524)
				)
			)
		)
		(property "Device Type" "C603H36"
			(at 0 -4.3434 270)
			(unlocked yes)
			(layer "F.Fab")
			(hide yes)
			(effects
				(font
					(size 1.016 1.016)
					(thickness 0.1524)
				)
			)
		)
		(duplicate_pad_numbers_are_jumpers no)
		(fp_line
			(start 0.508 0)
			(end -0.508 0)
			(stroke
				(width 0.2032)
				(type default)
			)
			(layer "F.SilkS")
		)
		(fp_rect
			(start -0.5842 1.3335)
			(end 0.5842 -1.3335)
			(stroke
				(width 0)
				(type default)
			)
			(fill no)
			(layer "F.CrtYd")
		)
		(fp_rect
			(start -0.5842 1.3335)
			(end 0.5842 -1.3335)
			(stroke
				(width 0)
				(type default)
			)
			(fill no)
			(layer "F.Fab")
		)
		(pad "1" smd custom
			(at 0 -0.762 270)
			(size 0.2159 0.2159)
			(layers "F.Cu" "F.Mask" "F.Paste")
			(net "P3V3_STBY_B")
			(options
				(clearance outline)
				(anchor circle)
			)
			(primitives
				(gr_poly
					(pts
						(arc
							(start -0.3302 -0.4318)
							(mid -0.402042 -0.402042)
							(end -0.4318 -0.3302)
						)
						(arc
							(start -0.4318 0.3302)
							(mid -0.402042 0.402042)
							(end -0.3302 0.4318)
						)
						(arc
							(start 0.3302 0.4318)
							(mid 0.402042 0.402042)
							(end 0.4318 0.3302)
						)
						(arc
							(start 0.4318 -0.3302)
							(mid 0.402042 -0.402042)
							(end 0.3302 -0.4318)
						)
					)
					(width 0)
					(fill yes)
				)
			)
		)
		(pad "2" smd custom
			(at 0 0.762 270)
			(size 0.2159 0.2159)
			(layers "F.Cu" "F.Mask" "F.Paste")
			(net "GND")
			(options
				(clearance outline)
				(anchor circle)
			)
			(primitives
				(gr_poly
					(pts
						(arc
							(start -0.3302 -0.4318)
							(mid -0.402042 -0.402042)
							(end -0.4318 -0.3302)
						)
						(arc
							(start -0.4318 0.3302)
							(mid -0.402042 0.402042)
							(end -0.3302 0.4318)
						)
						(arc
							(start 0.3302 0.4318)
							(mid 0.402042 0.402042)
							(end 0.4318 0.3302)
						)
						(arc
							(start 0.4318 -0.3302)
							(mid 0.402042 -0.402042)
							(end 0.3302 -0.4318)
						)
					)
					(width 0)
					(fill yes)
				)
			)
		)
	)
	(footprint ""
		(layer "F.Cu")
		(at 468.354918 -161.018474 -90)
		(property "Reference" "R676"
			(at 0 0 270)
			(layer "F.SilkS")
			(hide yes)
			(effects
				(font
					(size 1.27 1.27)
				)
			)
		)
		(property "Value" "0R2J-2-GP"
			(at 0.064008 -3.993896 270)
			(unlocked yes)
			(layer "F.Fab")
			(hide yes)
			(effects
				(font
					(size 1.016 1.016)
					(thickness 0.1524)
				)
			)
		)
		(property "Device Type" "R402H16"
			(at 0.064008 -5.517896 270)
			(unlocked yes)
			(layer "F.Fab")
			(hide yes)
			(effects
				(font
					(size 1.016 1.016)
					(thickness 0.1524)
				)
			)
		)
		(duplicate_pad_numbers_are_jumpers no)
		(fp_line
			(start -0.508 -0.9398)
			(end -0.508 0.9398)
			(stroke
				(width 0.1524)
				(type default)
			)
			(layer "F.SilkS")
		)
		(fp_line
			(start 0.508 -0.9398)
			(end -0.508 -0.9398)
			(stroke
				(width 0.1524)
				(type default)
			)
			(layer "F.SilkS")
		)
		(fp_rect
			(start -0.508 0.9398)
			(end 0.508 -0.9398)
			(stroke
				(width 0)
				(type default)
			)
			(fill no)
			(layer "F.CrtYd")
		)
		(fp_rect
			(start -0.508 0.9398)
			(end 0.508 -0.9398)
			(stroke
				(width 0)
				(type default)
			)
			(fill no)
			(layer "F.Fab")
		)
		(pad "1" smd custom
			(at 0 -0.4445 270)
			(size 0.1397 0.1397)
			(layers "F.Cu" "F.Mask" "F.Paste")
			(net "SW_HDD_G23")
			(options
				(clearance outline)
				(anchor circle)
			)
			(primitives
				(gr_poly
					(pts
						(arc
							(start -0.1778 -0.2794)
							(mid -0.249642 -0.249642)
							(end -0.2794 -0.1778)
						)
						(arc
							(start -0.2794 0.1778)
							(mid -0.249642 0.249642)
							(end -0.1778 0.2794)
						)
						(arc
							(start 0.1778 0.2794)
							(mid 0.249642 0.249642)
							(end 0.2794 0.1778)
						)
						(arc
							(start 0.2794 -0.1778)
							(mid 0.249642 -0.249642)
							(end 0.1778 -0.2794)
						)
					)
					(width 0)
					(fill yes)
				)
			)
		)
		(pad "2" smd custom
			(at 0 0.4445 270)
			(size 0.1397 0.1397)
			(layers "F.Cu" "F.Mask" "F.Paste")
			(net "SW_HDD_R23")
			(options
				(clearance outline)
				(anchor circle)
			)
			(primitives
				(gr_poly
					(pts
						(arc
							(start -0.1778 -0.2794)
							(mid -0.249642 -0.249642)
							(end -0.2794 -0.1778)
						)
						(arc
							(start -0.2794 0.1778)
							(mid -0.249642 0.249642)
							(end -0.1778 0.2794)
						)
						(arc
							(start 0.1778 0.2794)
							(mid 0.249642 0.249642)
							(end 0.2794 0.1778)
						)
						(arc
							(start 0.2794 -0.1778)
							(mid 0.249642 -0.249642)
							(end 0.1778 -0.2794)
						)
					)
					(width 0)
					(fill yes)
				)
			)
		)
	)
	(footprint ""
		(layer "F.Cu")
		(at 303.090072 -12.183872 90)
		(property "Reference" "C41"
			(at 0 0 90)
			(layer "F.SilkS")
			(hide yes)
			(effects
				(font
					(size 1.27 1.27)
				)
			)
		)
		(property "Value" "SC22U25V6KX-2-GP-U"
			(at -2.860802 -5.279644 90)
			(unlocked yes)
			(layer "F.Fab")
			(hide yes)
			(effects
				(font
					(size 1.016 1.016)
					(thickness 0.1524)
				)
			)
		)
		(property "Device Type" "C1206-TO0D3H75"
			(at -2.860802 -6.803644 90)
			(unlocked yes)
			(layer "F.Fab")
			(hide yes)
			(effects
				(font
					(size 1.016 1.016)
					(thickness 0.1524)
				)
			)
		)
		(duplicate_pad_numbers_are_jumpers no)
		(fp_line
			(start 1.3081 -2.3749)
			(end 1.3081 2.3749)
			(stroke
				(width 0.1524)
				(type default)
			)
			(layer "F.SilkS")
		)
		(fp_line
			(start -1.3081 -2.3749)
			(end 1.3081 -2.3749)
			(stroke
				(width 0.1524)
				(type default)
			)
			(layer "F.SilkS")
		)
		(fp_line
			(start 1.3081 2.3749)
			(end -1.3081 2.3749)
			(stroke
				(width 0.1524)
				(type default)
			)
			(layer "F.SilkS")
		)
		(fp_line
			(start -1.3081 2.3749)
			(end -1.3081 -2.3749)
			(stroke
				(width 0.1524)
				(type default)
			)
			(layer "F.SilkS")
		)
		(fp_rect
			(start -0.8001 1.6002)
			(end 0.8001 -1.6002)
			(stroke
				(width 0)
				(type default)
			)
			(fill no)
			(layer "F.CrtYd")
		)
		(fp_poly
			(pts
				(xy -1.5621 2.4511) (xy -1.5621 1.6002) (xy 0.8001 1.6002) (xy 0.8001 -1.6002) (xy -0.8001 -1.6002)
				(xy -0.8001 1.5875) (xy -1.5621 1.5875) (xy -1.5621 -2.4511) (xy 1.5621 -2.4511) (xy 1.5621 2.4511)
			)
			(stroke
				(width 0)
				(type default)
			)
			(fill no)
			(layer "F.CrtYd")
		)
		(fp_rect
			(start -1.5621 2.4511)
			(end 1.5621 -2.4511)
			(stroke
				(width 0)
				(type default)
			)
			(fill no)
			(layer "F.Fab")
		)
		(pad "1" smd rect
			(at 0 -1.392936 90)
			(size 2.1082 1.4478)
			(layers "F.Cu" "F.Mask" "F.Paste")
			(net "P12V_B_COMP")
		)
		(pad "2" smd rect
			(at 0 1.392936 90)
			(size 2.1082 1.4478)
			(layers "F.Cu" "F.Mask" "F.Paste")
			(net "GND")
		)
	)
	(footprint ""
		(layer "F.Cu")
		(at 456.0189 -181.842918 180)
		(property "Reference" "C326"
			(at 0 0 180)
			(layer "F.SilkS")
			(hide yes)
			(effects
				(font
					(size 1.27 1.27)
				)
			)
		)
		(property "Value" "SC1U16V3KX-5GP"
			(at 0 -2.8194 180)
			(unlocked yes)
			(layer "F.Fab")
			(hide yes)
			(effects
				(font
					(size 1.016 1.016)
					(thickness 0.1524)
				)
			)
		)
		(property "Device Type" "C603H36"
			(at 0 -4.3434 180)
			(unlocked yes)
			(layer "F.Fab")
			(hide yes)
			(effects
				(font
					(size 1.016 1.016)
					(thickness 0.1524)
				)
			)
		)
		(duplicate_pad_numbers_are_jumpers no)
		(fp_line
			(start 0.508 0)
			(end -0.508 0)
			(stroke
				(width 0.2032)
				(type default)
			)
			(layer "F.SilkS")
		)
		(fp_rect
			(start -0.5842 1.3335)
			(end 0.5842 -1.3335)
			(stroke
				(width 0)
				(type default)
			)
			(fill no)
			(layer "F.CrtYd")
		)
		(fp_rect
			(start -0.5842 1.3335)
			(end 0.5842 -1.3335)
			(stroke
				(width 0)
				(type default)
			)
			(fill no)
			(layer "F.Fab")
		)
		(pad "1" smd custom
			(at 0 -0.762 180)
			(size 0.2159 0.2159)
			(layers "F.Cu" "F.Mask" "F.Paste")
			(net "P5V_HDD22")
			(options
				(clearance outline)
				(anchor circle)
			)
			(primitives
				(gr_poly
					(pts
						(arc
							(start -0.3302 -0.4318)
							(mid -0.402042 -0.402042)
							(end -0.4318 -0.3302)
						)
						(arc
							(start -0.4318 0.3302)
							(mid -0.402042 0.402042)
							(end -0.3302 0.4318)
						)
						(arc
							(start 0.3302 0.4318)
							(mid 0.402042 0.402042)
							(end 0.4318 0.3302)
						)
						(arc
							(start 0.4318 -0.3302)
							(mid 0.402042 -0.402042)
							(end 0.3302 -0.4318)
						)
					)
					(width 0)
					(fill yes)
				)
			)
		)
		(pad "2" smd custom
			(at 0 0.762 180)
			(size 0.2159 0.2159)
			(layers "F.Cu" "F.Mask" "F.Paste")
			(net "GND")
			(options
				(clearance outline)
				(anchor circle)
			)
			(primitives
				(gr_poly
					(pts
						(arc
							(start -0.3302 -0.4318)
							(mid -0.402042 -0.402042)
							(end -0.4318 -0.3302)
						)
						(arc
							(start -0.4318 0.3302)
							(mid -0.402042 0.402042)
							(end -0.3302 0.4318)
						)
						(arc
							(start 0.3302 0.4318)
							(mid 0.402042 0.402042)
							(end 0.4318 0.3302)
						)
						(arc
							(start 0.4318 -0.3302)
							(mid 0.402042 -0.402042)
							(end 0.3302 -0.4318)
						)
					)
					(width 0)
					(fill yes)
				)
			)
		)
	)
	(footprint ""
		(layer "F.Cu")
		(at 130.274568 -187.489846)
		(property "Reference" "R471"
			(at 0 0 0)
			(layer "F.SilkS")
			(hide yes)
			(effects
				(font
					(size 1.27 1.27)
				)
			)
		)
		(property "Value" "4K7R2J-2-GP"
			(at 0.064008 -3.993896 0)
			(unlocked yes)
			(layer "F.Fab")
			(hide yes)
			(effects
				(font
					(size 1.016 1.016)
					(thickness 0.1524)
				)
			)
		)
		(property "Device Type" "R402H16"
			(at 0.064008 -5.517896 0)
			(unlocked yes)
			(layer "F.Fab")
			(hide yes)
			(effects
				(font
					(size 1.016 1.016)
					(thickness 0.1524)
				)
			)
		)
		(duplicate_pad_numbers_are_jumpers no)
		(fp_line
			(start -0.508 -0.9398)
			(end -0.508 0.9398)
			(stroke
				(width 0.1524)
				(type default)
			)
			(layer "F.SilkS")
		)
		(fp_line
			(start 0.508 -0.9398)
			(end -0.508 -0.9398)
			(stroke
				(width 0.1524)
				(type default)
			)
			(layer "F.SilkS")
		)
		(fp_rect
			(start -0.508 0.9398)
			(end 0.508 -0.9398)
			(stroke
				(width 0)
				(type default)
			)
			(fill no)
			(layer "F.CrtYd")
		)
		(fp_rect
			(start -0.508 0.9398)
			(end 0.508 -0.9398)
			(stroke
				(width 0)
				(type default)
			)
			(fill no)
			(layer "F.Fab")
		)
		(pad "1" smd custom
			(at 0 -0.4445)
			(size 0.1397 0.1397)
			(layers "F.Cu" "F.Mask" "F.Paste")
			(net "DRIVE_A_4_FLT_LED")
			(options
				(clearance outline)
				(anchor circle)
			)
			(primitives
				(gr_poly
					(pts
						(arc
							(start -0.1778 -0.2794)
							(mid -0.249642 -0.249642)
							(end -0.2794 -0.1778)
						)
						(arc
							(start -0.2794 0.1778)
							(mid -0.249642 0.249642)
							(end -0.1778 0.2794)
						)
						(arc
							(start 0.1778 0.2794)
							(mid 0.249642 0.249642)
							(end 0.2794 0.1778)
						)
						(arc
							(start 0.2794 -0.1778)
							(mid 0.249642 -0.249642)
							(end 0.1778 -0.2794)
						)
					)
					(width 0)
					(fill yes)
				)
			)
		)
		(pad "2" smd custom
			(at 0 0.4445)
			(size 0.1397 0.1397)
			(layers "F.Cu" "F.Mask" "F.Paste")
			(net "GND")
			(options
				(clearance outline)
				(anchor circle)
			)
			(primitives
				(gr_poly
					(pts
						(arc
							(start -0.1778 -0.2794)
							(mid -0.249642 -0.249642)
							(end -0.2794 -0.1778)
						)
						(arc
							(start -0.2794 0.1778)
							(mid -0.249642 0.249642)
							(end -0.1778 0.2794)
						)
						(arc
							(start 0.1778 0.2794)
							(mid 0.249642 0.249642)
							(end 0.2794 0.1778)
						)
						(arc
							(start 0.2794 -0.1778)
							(mid 0.249642 -0.249642)
							(end 0.1778 -0.2794)
						)
					)
					(width 0)
					(fill yes)
				)
			)
		)
	)
	(footprint ""
		(layer "F.Cu")
		(at 190.258954 -162.749992 -90)
		(property "Reference" "VIA56"
			(at 0 0 270)
			(layer "F.SilkS")
			(hide yes)
			(effects
				(font
					(size 1.27 1.27)
				)
			)
		)
		(property "Value" "100OHM-8L-1D6MM-L18L16-GP"
			(at -3.7211 -4.5085 270)
			(unlocked yes)
			(layer "F.Fab")
			(hide yes)
			(effects
				(font
					(size 1.016 1.016)
					(thickness 0.1524)
				)
			)
		)
		(property "Device Type" "VIA-PCIE-4P-394076"
			(at -3.7211 -6.0325 270)
			(unlocked yes)
			(layer "F.Fab")
			(hide yes)
			(effects
				(font
					(size 1.016 1.016)
					(thickness 0.1524)
				)
			)
		)
		(duplicate_pad_numbers_are_jumpers no)
		(fp_rect
			(start -1.9685 0.381)
			(end 1.9685 -0.381)
			(stroke
				(width 0)
				(type default)
			)
			(fill no)
			(layer "F.CrtYd")
		)
		(fp_rect
			(start -1.9685 0.381)
			(end 1.9685 -0.381)
			(stroke
				(width 0)
				(type default)
			)
			(fill no)
			(layer "F.Fab")
		)
		(pad "1" thru_hole circle
			(at -1.5875 0 270)
			(size 0.508 0.508)
			(drill 0.254)
			(layers "*.Cu" "*.Mask")
			(remove_unused_layers no)
			(net "GND")
			(clearance 0.127)
			(thermal_gap 0.127)
		)
		(pad "2" thru_hole circle
			(at -0.5715 0 270)
			(size 0.508 0.508)
			(drill 0.254)
			(layers "*.Cu" "*.Mask")
			(remove_unused_layers no)
			(net "PHY_DRV_A_TO_SCC_A_17_DP")
			(clearance 0.127)
			(thermal_gap 0.127)
		)
		(pad "3" thru_hole circle
			(at 0.5715 0 270)
			(size 0.508 0.508)
			(drill 0.254)
			(layers "*.Cu" "*.Mask")
			(remove_unused_layers no)
			(net "PHY_DRV_A_TO_SCC_A_17_DN")
			(clearance 0.127)
			(thermal_gap 0.127)
		)
		(pad "4" thru_hole circle
			(at 1.5875 0 270)
			(size 0.508 0.508)
			(drill 0.254)
			(layers "*.Cu" "*.Mask")
			(remove_unused_layers no)
			(net "GND")
			(clearance 0.127)
			(thermal_gap 0.127)
		)
	)
	(footprint ""
		(layer "F.Cu")
		(at 257.345688 -138.482578 90)
		(property "Reference" "R1003"
			(at 0 0 90)
			(layer "F.SilkS")
			(hide yes)
			(effects
				(font
					(size 1.27 1.27)
				)
			)
		)
		(property "Value" "100KR2F-L1-GP"
			(at 0.064008 -3.993896 90)
			(unlocked yes)
			(layer "F.Fab")
			(hide yes)
			(effects
				(font
					(size 1.016 1.016)
					(thickness 0.1524)
				)
			)
		)
		(property "Device Type" "R402H16"
			(at 0.064008 -5.517896 90)
			(unlocked yes)
			(layer "F.Fab")
			(hide yes)
			(effects
				(font
					(size 1.016 1.016)
					(thickness 0.1524)
				)
			)
		)
		(duplicate_pad_numbers_are_jumpers no)
		(fp_line
			(start 0.508 -0.9398)
			(end -0.508 -0.9398)
			(stroke
				(width 0.1524)
				(type default)
			)
			(layer "F.SilkS")
		)
		(fp_line
			(start -0.508 -0.9398)
			(end -0.508 0.9398)
			(stroke
				(width 0.1524)
				(type default)
			)
			(layer "F.SilkS")
		)
		(fp_rect
			(start -0.508 0.9398)
			(end 0.508 -0.9398)
			(stroke
				(width 0)
				(type default)
			)
			(fill no)
			(layer "F.CrtYd")
		)
		(fp_rect
			(start -0.508 0.9398)
			(end 0.508 -0.9398)
			(stroke
				(width 0)
				(type default)
			)
			(fill no)
			(layer "F.Fab")
		)
		(pad "1" smd custom
			(at 0 -0.4445 90)
			(size 0.1397 0.1397)
			(layers "F.Cu" "F.Mask" "F.Paste")
			(net "PCIE_COMP_A_TO_IOM_A_RST_2")
			(options
				(clearance outline)
				(anchor circle)
			)
			(primitives
				(gr_poly
					(pts
						(arc
							(start -0.1778 -0.2794)
							(mid -0.249642 -0.249642)
							(end -0.2794 -0.1778)
						)
						(arc
							(start -0.2794 0.1778)
							(mid -0.249642 0.249642)
							(end -0.1778 0.2794)
						)
						(arc
							(start 0.1778 0.2794)
							(mid 0.249642 0.249642)
							(end 0.2794 0.1778)
						)
						(arc
							(start 0.2794 -0.1778)
							(mid 0.249642 -0.249642)
							(end 0.1778 -0.2794)
						)
					)
					(width 0)
					(fill yes)
				)
			)
		)
		(pad "2" smd custom
			(at 0 0.4445 90)
			(size 0.1397 0.1397)
			(layers "F.Cu" "F.Mask" "F.Paste")
			(net "GND")
			(options
				(clearance outline)
				(anchor circle)
			)
			(primitives
				(gr_poly
					(pts
						(arc
							(start -0.1778 -0.2794)
							(mid -0.249642 -0.249642)
							(end -0.2794 -0.1778)
						)
						(arc
							(start -0.2794 0.1778)
							(mid -0.249642 0.249642)
							(end -0.1778 0.2794)
						)
						(arc
							(start 0.1778 0.2794)
							(mid 0.249642 0.249642)
							(end 0.2794 0.1778)
						)
						(arc
							(start 0.2794 -0.1778)
							(mid 0.249642 -0.249642)
							(end 0.1778 -0.2794)
						)
					)
					(width 0)
					(fill yes)
				)
			)
		)
	)
	(footprint ""
		(layer "F.Cu")
		(at 95.563436 -274.219416 90)
		(property "Reference" "C64"
			(at 0 0 90)
			(layer "F.SilkS")
			(hide yes)
			(effects
				(font
					(size 1.27 1.27)
				)
			)
		)
		(property "Value" "SCD01U16V1KX-GP"
			(at -2.8321 -1.7399 90)
			(unlocked yes)
			(layer "F.Fab")
			(hide yes)
			(effects
				(font
					(size 1.016 1.016)
					(thickness 0.1524)
				)
			)
		)
		(property "Device Type" "C0201H13"
			(at -2.8321 -3.2639 90)
			(unlocked yes)
			(layer "F.Fab")
			(hide yes)
			(effects
				(font
					(size 1.016 1.016)
					(thickness 0.1524)
				)
			)
		)
		(duplicate_pad_numbers_are_jumpers no)
		(fp_rect
			(start -0.2794 0.6477)
			(end 0.2794 -0.6477)
			(stroke
				(width 0)
				(type default)
			)
			(fill no)
			(layer "F.CrtYd")
		)
		(fp_rect
			(start -0.2794 0.6477)
			(end 0.2794 -0.6477)
			(stroke
				(width 0)
				(type default)
			)
			(fill no)
			(layer "F.Fab")
		)
		(pad "1" smd custom
			(at 0 -0.2794 90)
			(size 0.0762 0.0762)
			(layers "F.Cu" "F.Mask" "F.Paste")
			(net "SAS_HDD_RX_N2")
			(options
				(clearance outline)
				(anchor circle)
			)
			(primitives
				(gr_poly
					(pts
						(arc
							(start 0.1524 -0.127)
							(mid 0.137521 -0.162921)
							(end 0.1016 -0.1778)
						)
						(arc
							(start -0.1016 -0.1778)
							(mid -0.137521 -0.162921)
							(end -0.1524 -0.127)
						)
						(arc
							(start -0.1524 0.127)
							(mid -0.137521 0.162921)
							(end -0.1016 0.1778)
						)
						(arc
							(start 0.1016 0.1778)
							(mid 0.137521 0.162921)
							(end 0.1524 0.127)
						)
					)
					(width 0)
					(fill yes)
				)
			)
		)
		(pad "2" smd custom
			(at 0 0.2794 90)
			(size 0.0762 0.0762)
			(layers "F.Cu" "F.Mask" "F.Paste")
			(net "PHY_SCC_A_TO_DRV_A_2_DN")
			(options
				(clearance outline)
				(anchor circle)
			)
			(primitives
				(gr_poly
					(pts
						(arc
							(start 0.1524 -0.127)
							(mid 0.137521 -0.162921)
							(end 0.1016 -0.1778)
						)
						(arc
							(start -0.1016 -0.1778)
							(mid -0.137521 -0.162921)
							(end -0.1524 -0.127)
						)
						(arc
							(start -0.1524 0.127)
							(mid -0.137521 0.162921)
							(end -0.1016 0.1778)
						)
						(arc
							(start 0.1016 0.1778)
							(mid 0.137521 0.162921)
							(end 0.1524 0.127)
						)
					)
					(width 0)
					(fill yes)
				)
			)
		)
	)
)
